# BASEBOARD_FAB2 (Tioga Pass) — schematic netlist excerpt (pin names and nets, part order shuffled) for the footprints in the layout excerpt that follows; sources: Cadence DE-HDL packaged netlist, KiCad conversion of Wiwynn_Tioga_Pass_MB.brd

R6P48  RES  1.00K 1% CHIP  pkg 0402  page 102 : A = P3V3 ; B = FM_DB1200ZL_BCLKS_EN_N
R7D1  RES  1.00K 1% EMPTY  pkg 0402  page 125 : A = RMII_PCH_SPRNGVLLE_ARB_OUT ; B = GND
C6P6  CAP_A  0.1UF 16V 10% X7R  pkg 0402V  page 102 : A = P3V3_DB1200 ; B = GND

(kicad_pcb
	(version 20260206)
	(generator "pcbnew")
	(generator_version "10.0")
	(general
		(thickness 1.6)
		(legacy_teardrops no)
	)
	(paper "A4")
	(title_block
		(title "Wiwynn_Tioga_Pass_MB.brd")
		(comment 1 "Tioga Pass / footprints 3619-3621 of 4770")
	)
	(layers
		(0 "F.Cu" signal "TOP")
		(4 "In1.Cu" signal "L2GND")
		(6 "In2.Cu" signal "L3")
		(8 "In3.Cu" signal "L4GND")
		(10 "In4.Cu" signal "L5")
		(12 "In5.Cu" signal "L6GND")
		(14 "In6.Cu" signal "L7VCC")
		(16 "In7.Cu" signal "L8VCC")
		(18 "In8.Cu" signal "L9GND")
		(20 "In9.Cu" signal "L10")
		(22 "In10.Cu" signal "L11GND")
		(24 "In11.Cu" signal "L12")
		(26 "In12.Cu" signal "L13GND")
		(2 "B.Cu" signal "BOTTOM")
		(9 "F.Adhes" user "F.Adhesive")
		(11 "B.Adhes" user "B.Adhesive")
		(13 "F.Paste" user "Package Geometry/Pastemask Top")
		(15 "B.Paste" user "Package Geometry/Pastemask Bottom")
		(5 "F.SilkS" user "Ref Des/Silkscreen Top")
		(7 "B.SilkS" user "Ref Des/Silkscreen Bottom")
		(1 "F.Mask" user "Board Geometry/Soldermask Top")
		(3 "B.Mask" user "Board Geometry/Soldermask Bottom")
		(17 "Dwgs.User" user "User.Drawings")
		(19 "Cmts.User" user "User.Comments")
		(21 "Eco1.User" user "User.Eco1")
		(23 "Eco2.User" user "User.Eco2")
		(25 "Edge.Cuts" user "Board Geometry/Outline")
		(27 "Margin" user)
		(31 "F.CrtYd" user "Package Geometry/Place Bound Top")
		(29 "B.CrtYd" user "Package Geometry/Place Bound Bottom")
		(35 "F.Fab" user "Ref Des/Assembly Top")
		(33 "B.Fab" user "Ref Des/Assembly Bottom")
	)
	(footprint ""
		(layer "B.Cu")
		(at 173.863 -84.582 -90)
		(property "Reference" "C6P6"
			(at 0 0 90)
			(layer "B.SilkS")
			(hide yes)
			(effects
				(font
					(size 1.27 1.27)
				)
				(justify mirror)
			)
		)
		(property "Value" ""
			(at 0 0 90)
			(layer "B.Fab")
			(effects
				(font
					(size 1.27 1.27)
				)
				(justify mirror)
			)
		)
		(duplicate_pad_numbers_are_jumpers no)
		(fp_poly
			(pts
				(xy -0.3048 -0.1016) (xy -0.3048 0.9906) (xy 0.3048 0.9906) (xy 0.3048 -0.1016)
			)
			(stroke
				(width 0)
				(type default)
			)
			(fill no)
			(layer "B.CrtYd")
		)
		(fp_line
			(start -0.3048 0.9906)
			(end -0.3048 -0.1016)
			(stroke
				(width 0.1)
				(type default)
			)
			(layer "B.Fab")
		)
		(fp_line
			(start 0.3048 0.9906)
			(end -0.3048 0.9906)
			(stroke
				(width 0.1)
				(type default)
			)
			(layer "B.Fab")
		)
		(fp_line
			(start -0.3048 -0.1016)
			(end 0.3048 -0.1016)
			(stroke
				(width 0.1)
				(type default)
			)
			(layer "B.Fab")
		)
		(fp_line
			(start 0.3048 -0.1016)
			(end 0.3048 0.9906)
			(stroke
				(width 0.1)
				(type default)
			)
			(layer "B.Fab")
		)
		(pad "1" smd rect
			(at 0 0 90)
			(size 0.508 0.508)
			(layers "B.Cu" "B.Mask" "B.Paste")
			(net "P3V3_DB1200")
		)
		(pad "2" smd rect
			(at 0 0.889 90)
			(size 0.508 0.508)
			(layers "B.Cu" "B.Mask" "B.Paste")
			(net "GND")
		)
		(zone
			(layer "B.Cu")
			(hatch none 0.5)
			(connect_pads
				(clearance 0)
			)
			(min_thickness 0.25)
			(keepout
				(tracks not_allowed)
				(vias allowed)
				(pads allowed)
				(copperpour not_allowed)
				(footprints allowed)
			)
			(placement
				(enabled no)
				(sheetname "")
			)
			(fill
				(thermal_gap 0.5)
				(thermal_bridge_width 0.5)
				(island_removal_mode 0)
			)
			(polygon
				(pts
					(xy 173.228 -84.328) (xy 173.228 -84.836) (xy 173.609 -84.836) (xy 173.609 -84.328)
				)
			)
		)
		(zone
			(layer "B.Cu")
			(hatch none 0.5)
			(connect_pads
				(clearance 0)
			)
			(min_thickness 0.25)
			(keepout
				(tracks allowed)
				(vias not_allowed)
				(pads allowed)
				(copperpour not_allowed)
				(footprints allowed)
			)
			(placement
				(enabled no)
				(sheetname "")
			)
			(fill
				(thermal_gap 0.5)
				(thermal_bridge_width 0.5)
				(island_removal_mode 0)
			)
			(polygon
				(pts
					(xy 173.609 -84.328) (xy 173.609 -84.836) (xy 173.228 -84.836) (xy 173.228 -84.328)
				)
			)
		)
	)
	(footprint ""
		(layer "B.Cu")
		(at 388.64794 -84.75472 -90)
		(property "Reference" "R7D1"
			(at 0.8382 -0.67818 270)
			(unlocked yes)
			(layer "B.SilkS")
			(effects
				(font
					(size 0.4064 0.254)
					(thickness 0.1524)
				)
				(justify left mirror)
			)
		)
		(property "Value" ""
			(at 0 0 90)
			(layer "B.Fab")
			(effects
				(font
					(size 1.27 1.27)
				)
				(justify mirror)
			)
		)
		(duplicate_pad_numbers_are_jumpers no)
		(fp_poly
			(pts
				(xy 0.2794 -0.1016) (xy -0.2794 -0.1016) (xy -0.2794 0.9906) (xy 0.2794 0.9906)
			)
			(stroke
				(width 0)
				(type default)
			)
			(fill no)
			(layer "B.CrtYd")
		)
		(fp_line
			(start -0.2794 0.9906)
			(end -0.2794 -0.1016)
			(stroke
				(width 0.1)
				(type default)
			)
			(layer "B.Fab")
		)
		(fp_line
			(start 0.2794 0.9906)
			(end -0.2794 0.9906)
			(stroke
				(width 0.1)
				(type default)
			)
			(layer "B.Fab")
		)
		(fp_line
			(start -0.2794 -0.1016)
			(end 0.2794 -0.1016)
			(stroke
				(width 0.1)
				(type default)
			)
			(layer "B.Fab")
		)
		(fp_line
			(start 0.2794 -0.1016)
			(end 0.2794 0.9906)
			(stroke
				(width 0.1)
				(type default)
			)
			(layer "B.Fab")
		)
		(pad "1" smd rect
			(at 0 0 90)
			(size 0.508 0.508)
			(layers "B.Cu" "B.Mask" "B.Paste")
			(net "RMII_PCH_SPRNGVLLE_ARB_OUT")
		)
		(pad "2" smd rect
			(at 0 0.889 90)
			(size 0.508 0.508)
			(layers "B.Cu" "B.Mask" "B.Paste")
			(net "GND")
		)
		(zone
			(layer "B.Cu")
			(hatch none 0.5)
			(connect_pads
				(clearance 0)
			)
			(min_thickness 0.25)
			(keepout
				(tracks not_allowed)
				(vias allowed)
				(pads allowed)
				(copperpour not_allowed)
				(footprints allowed)
			)
			(placement
				(enabled no)
				(sheetname "")
			)
			(fill
				(thermal_gap 0.5)
				(thermal_bridge_width 0.5)
				(island_removal_mode 0)
			)
			(polygon
				(pts
					(xy 388.01294 -84.50072) (xy 388.01294 -85.00872) (xy 388.39394 -85.00872) (xy 388.39394 -84.50072)
				)
			)
		)
		(zone
			(layer "B.Cu")
			(hatch none 0.5)
			(connect_pads
				(clearance 0)
			)
			(min_thickness 0.25)
			(keepout
				(tracks allowed)
				(vias not_allowed)
				(pads allowed)
				(copperpour not_allowed)
				(footprints allowed)
			)
			(placement
				(enabled no)
				(sheetname "")
			)
			(fill
				(thermal_gap 0.5)
				(thermal_bridge_width 0.5)
				(island_removal_mode 0)
			)
			(polygon
				(pts
					(xy 388.39394 -84.50072) (xy 388.39394 -85.00872) (xy 388.01294 -85.00872) (xy 388.01294 -84.50072)
				)
			)
		)
	)
	(footprint ""
		(layer "B.Cu")
		(at 177.927 -79.121)
		(property "Reference" "R6P48"
			(at 0 0 0)
			(layer "B.SilkS")
			(hide yes)
			(effects
				(font
					(size 1.27 1.27)
				)
				(justify mirror)
			)
		)
		(property "Value" ""
			(at 0 0 0)
			(layer "B.Fab")
			(effects
				(font
					(size 1.27 1.27)
				)
				(justify mirror)
			)
		)
		(duplicate_pad_numbers_are_jumpers no)
		(fp_poly
			(pts
				(xy 0.2794 -0.1016) (xy -0.2794 -0.1016) (xy -0.2794 0.9906) (xy 0.2794 0.9906)
			)
			(stroke
				(width 0)
				(type default)
			)
			(fill no)
			(layer "B.CrtYd")
		)
		(fp_line
			(start -0.2794 -0.1016)
			(end 0.2794 -0.1016)
			(stroke
				(width 0.1)
				(type default)
			)
			(layer "B.Fab")
		)
		(fp_line
			(start -0.2794 0.9906)
			(end -0.2794 -0.1016)
			(stroke
				(width 0.1)
				(type default)
			)
			(layer "B.Fab")
		)
		(fp_line
			(start 0.2794 -0.1016)
			(end 0.2794 0.9906)
			(stroke
				(width 0.1)
				(type default)
			)
			(layer "B.Fab")
		)
		(fp_line
			(start 0.2794 0.9906)
			(end -0.2794 0.9906)
			(stroke
				(width 0.1)
				(type default)
			)
			(layer "B.Fab")
		)
		(pad "1" smd rect
			(at 0 0 180)
			(size 0.508 0.508)
			(layers "B.Cu" "B.Mask" "B.Paste")
			(net "P3V3")
		)
		(pad "2" smd rect
			(at 0 0.889 180)
			(size 0.508 0.508)
			(layers "B.Cu" "B.Mask" "B.Paste")
			(net "FM_DB1200ZL_BCLKS_EN_N")
		)
		(zone
			(layer "B.Cu")
			(hatch none 0.5)
			(connect_pads
				(clearance 0)
			)
			(min_thickness 0.25)
			(keepout
				(tracks allowed)
				(vias not_allowed)
				(pads allowed)
				(copperpour not_allowed)
				(footprints allowed)
			)
			(placement
				(enabled no)
				(sheetname "")
			)
			(fill
				(thermal_gap 0.5)
				(thermal_bridge_width 0.5)
				(island_removal_mode 0)
			)
			(polygon
				(pts
					(xy 178.181 -78.867) (xy 177.673 -78.867) (xy 177.673 -78.486) (xy 178.181 -78.486)
				)
			)
		)
		(zone
			(layer "B.Cu")
			(hatch none 0.5)
			(connect_pads
				(clearance 0)
			)
			(min_thickness 0.25)
			(keepout
				(tracks not_allowed)
				(vias allowed)
				(pads allowed)
				(copperpour not_allowed)
				(footprints allowed)
			)
			(placement
				(enabled no)
				(sheetname "")
			)
			(fill
				(thermal_gap 0.5)
				(thermal_bridge_width 0.5)
				(island_removal_mode 0)
			)
			(polygon
				(pts
					(xy 178.181 -78.486) (xy 177.673 -78.486) (xy 177.673 -78.867) (xy 178.181 -78.867)
				)
			)
		)
	)
)
